# BASEBOARD_FAB2 (Tioga Pass) — schematic netlist excerpt (pin names and nets, part order shuffled) for the footprints in the layout excerpt that follows; sources: Cadence DE-HDL packaged netlist, KiCad conversion of Wiwynn_Tioga_Pass_MB.brd

R2T64  RES  0.0 5% CHIP  pkg 0402  page 93 : A = FM_CPU_ERR1_LVT3_N ; B = FM_CPU_ERR1_LVT3_BMC_N

U9B4  TMP421  IC  pkg TSSOP  page 167
  DXP  = ISENSE_TMP421_1_DXP
  DXN  = ISENSE_TMP421_1_DXN
  A(1)  = PU_TMP421_1_A1
  A(0)  = PD_TMP421_1_A0
  GND  = GND
  SDA  = SMB_SENSOR_TMP421_1_SDA
  SCL  = SMB_SENSOR_TMP421_1_SCL
  VP  = P3V3_STBY

C1F27  CAP  1.0UF 16V 10% X6S  pkg 0402  page 224 : A = VR_FET_SW_P12V_STBY_PVDDQ_GHJ ; B = GND

(kicad_pcb
	(version 20260206)
	(generator "pcbnew")
	(generator_version "10.0")
	(general
		(thickness 1.6)
		(legacy_teardrops no)
	)
	(paper "A4")
	(title_block
		(title "Wiwynn_Tioga_Pass_MB.brd")
		(comment 1 "Tioga Pass / footprints 1086-1088 of 4770")
	)
	(layers
		(0 "F.Cu" signal "TOP")
		(4 "In1.Cu" signal "L2GND")
		(6 "In2.Cu" signal "L3")
		(8 "In3.Cu" signal "L4GND")
		(10 "In4.Cu" signal "L5")
		(12 "In5.Cu" signal "L6GND")
		(14 "In6.Cu" signal "L7VCC")
		(16 "In7.Cu" signal "L8VCC")
		(18 "In8.Cu" signal "L9GND")
		(20 "In9.Cu" signal "L10")
		(22 "In10.Cu" signal "L11GND")
		(24 "In11.Cu" signal "L12")
		(26 "In12.Cu" signal "L13GND")
		(2 "B.Cu" signal "BOTTOM")
		(9 "F.Adhes" user "F.Adhesive")
		(11 "B.Adhes" user "B.Adhesive")
		(13 "F.Paste" user "Package Geometry/Pastemask Top")
		(15 "B.Paste" user "Package Geometry/Pastemask Bottom")
		(5 "F.SilkS" user "Ref Des/Silkscreen Top")
		(7 "B.SilkS" user "Ref Des/Silkscreen Bottom")
		(1 "F.Mask" user "Board Geometry/Soldermask Top")
		(3 "B.Mask" user "Board Geometry/Soldermask Bottom")
		(17 "Dwgs.User" user "User.Drawings")
		(19 "Cmts.User" user "User.Comments")
		(21 "Eco1.User" user "User.Eco1")
		(23 "Eco2.User" user "User.Eco2")
		(25 "Edge.Cuts" user "Board Geometry/Outline")
		(27 "Margin" user)
		(31 "F.CrtYd" user "Package Geometry/Place Bound Top")
		(29 "B.CrtYd" user "Package Geometry/Place Bound Bottom")
		(35 "F.Fab" user "Ref Des/Assembly Top")
		(33 "B.Fab" user "Ref Des/Assembly Bottom")
	)
	(footprint ""
		(layer "F.Cu")
		(at 0.635 -20.0406 -90)
		(property "Reference" "C1F27"
			(at 0 0 270)
			(layer "F.SilkS")
			(hide yes)
			(effects
				(font
					(size 1.27 1.27)
				)
			)
		)
		(property "Value" ""
			(at 0 0 270)
			(layer "F.Fab")
			(effects
				(font
					(size 1.27 1.27)
				)
			)
		)
		(duplicate_pad_numbers_are_jumpers no)
		(fp_poly
			(pts
				(xy 0.3048 -0.1016) (xy 0.3048 0.9906) (xy -0.3048 0.9906) (xy -0.3048 -0.1016)
			)
			(stroke
				(width 0)
				(type default)
			)
			(fill no)
			(layer "F.CrtYd")
		)
		(fp_line
			(start -0.3048 0.9906)
			(end 0.3048 0.9906)
			(stroke
				(width 0.1)
				(type default)
			)
			(layer "F.Fab")
		)
		(fp_line
			(start 0.3048 0.9906)
			(end 0.3048 -0.1016)
			(stroke
				(width 0.1)
				(type default)
			)
			(layer "F.Fab")
		)
		(fp_line
			(start -0.3048 -0.1016)
			(end -0.3048 0.9906)
			(stroke
				(width 0.1)
				(type default)
			)
			(layer "F.Fab")
		)
		(fp_line
			(start 0.3048 -0.1016)
			(end -0.3048 -0.1016)
			(stroke
				(width 0.1)
				(type default)
			)
			(layer "F.Fab")
		)
		(pad "1" smd rect
			(at 0 0 270)
			(size 0.508 0.508)
			(layers "F.Cu" "F.Mask" "F.Paste")
			(net "VR_FET_SW_P12V_STBY_PVDDQ_GHJ")
		)
		(pad "2" smd rect
			(at 0 0.889 270)
			(size 0.508 0.508)
			(layers "F.Cu" "F.Mask" "F.Paste")
			(net "GND")
		)
		(zone
			(layer "F.Cu")
			(hatch none 0.5)
			(connect_pads
				(clearance 0)
			)
			(min_thickness 0.25)
			(keepout
				(tracks not_allowed)
				(vias allowed)
				(pads allowed)
				(copperpour not_allowed)
				(footprints allowed)
			)
			(placement
				(enabled no)
				(sheetname "")
			)
			(fill
				(thermal_gap 0.5)
				(thermal_bridge_width 0.5)
				(island_removal_mode 0)
			)
			(polygon
				(pts
					(xy 0 -20.2946) (xy 0 -19.7866) (xy 0.381 -19.7866) (xy 0.381 -20.2946)
				)
			)
		)
		(zone
			(layer "F.Cu")
			(hatch none 0.5)
			(connect_pads
				(clearance 0)
			)
			(min_thickness 0.25)
			(keepout
				(tracks allowed)
				(vias not_allowed)
				(pads allowed)
				(copperpour not_allowed)
				(footprints allowed)
			)
			(placement
				(enabled no)
				(sheetname "")
			)
			(fill
				(thermal_gap 0.5)
				(thermal_bridge_width 0.5)
				(island_removal_mode 0)
			)
			(polygon
				(pts
					(xy 0.381 -20.2946) (xy 0.381 -19.7866) (xy 0 -19.7866) (xy 0 -20.2946)
				)
			)
		)
	)
	(footprint ""
		(layer "F.Cu")
		(at 488.6706 -123.75134)
		(property "Reference" "U9B4"
			(at 1.30302 5.01777 0)
			(unlocked yes)
			(layer "F.SilkS")
			(effects
				(font
					(size 0.7874 0.5842)
					(thickness 0.1524)
				)
			)
		)
		(property "Value" ""
			(at 0 0 0)
			(layer "F.Fab")
			(effects
				(font
					(size 1.27 1.27)
				)
			)
		)
		(duplicate_pad_numbers_are_jumpers no)
		(fp_line
			(start 1.566672 -0.52324)
			(end 0.985774 -0.52324)
			(stroke
				(width 0.1524)
				(type default)
			)
			(layer "F.SilkS")
		)
		(fp_line
			(start 1.583436 2.47396)
			(end 0.965454 2.47396)
			(stroke
				(width 0.1524)
				(type default)
			)
			(layer "F.SilkS")
		)
		(fp_circle
			(center -0.635 -0.889)
			(end -0.508 -0.889)
			(stroke
				(width 0.254)
				(type default)
			)
			(fill no)
			(layer "F.SilkS")
		)
		(fp_rect
			(start 0.3937 2.47396)
			(end 2.1463 -0.52324)
			(stroke
				(width 0)
				(type default)
			)
			(fill no)
			(layer "F.CrtYd")
		)
		(fp_line
			(start 0.3937 -0.52324)
			(end 2.1463 -0.52324)
			(stroke
				(width 0.1)
				(type default)
			)
			(layer "F.Fab")
		)
		(fp_line
			(start 0.3937 2.47396)
			(end 0.3937 -0.52324)
			(stroke
				(width 0.1)
				(type default)
			)
			(layer "F.Fab")
		)
		(fp_line
			(start 2.1463 -0.52324)
			(end 2.1463 2.47396)
			(stroke
				(width 0.1)
				(type default)
			)
			(layer "F.Fab")
		)
		(fp_line
			(start 2.1463 2.47396)
			(end 0.3937 2.47396)
			(stroke
				(width 0.1)
				(type default)
			)
			(layer "F.Fab")
		)
		(fp_circle
			(center -0.635 -0.889)
			(end -0.508 -0.889)
			(stroke
				(width 0.254)
				(type default)
			)
			(fill no)
			(layer "F.Fab")
		)
		(pad "1" smd rect
			(at 0 0)
			(size 1.27 0.381)
			(layers "F.Cu" "F.Mask" "F.Paste")
			(net "ISENSE_TMP421_1_DXP")
		)
		(pad "2" smd rect
			(at 0 0.65024)
			(size 1.27 0.381)
			(layers "F.Cu" "F.Mask" "F.Paste")
			(net "ISENSE_TMP421_1_DXN")
		)
		(pad "3" smd rect
			(at 0 1.30048)
			(size 1.27 0.381)
			(layers "F.Cu" "F.Mask" "F.Paste")
			(net "PU_TMP421_1_A1")
		)
		(pad "4" smd rect
			(at 0 1.95072)
			(size 1.27 0.381)
			(layers "F.Cu" "F.Mask" "F.Paste")
			(net "PD_TMP421_1_A0")
		)
		(pad "5" smd rect
			(at 2.54 1.95072)
			(size 1.27 0.381)
			(layers "F.Cu" "F.Mask" "F.Paste")
			(net "GND")
		)
		(pad "6" smd rect
			(at 2.54 1.30048)
			(size 1.27 0.381)
			(layers "F.Cu" "F.Mask" "F.Paste")
			(net "SMB_SENSOR_TMP421_1_SDA")
		)
		(pad "7" smd rect
			(at 2.54 0.65024)
			(size 1.27 0.381)
			(layers "F.Cu" "F.Mask" "F.Paste")
			(net "SMB_SENSOR_TMP421_1_SCL")
		)
		(pad "8" smd rect
			(at 2.54 0)
			(size 1.27 0.381)
			(layers "F.Cu" "F.Mask" "F.Paste")
			(net "P3V3_STBY")
		)
	)
	(footprint ""
		(layer "F.Cu")
		(at 406.146 -46.8249 180)
		(property "Reference" "R2T64"
			(at 0 0 180)
			(layer "F.SilkS")
			(hide yes)
			(effects
				(font
					(size 1.27 1.27)
				)
			)
		)
		(property "Value" ""
			(at 0 0 180)
			(layer "F.Fab")
			(effects
				(font
					(size 1.27 1.27)
				)
			)
		)
		(duplicate_pad_numbers_are_jumpers no)
		(fp_poly
			(pts
				(xy -0.2794 -0.1016) (xy 0.2794 -0.1016) (xy 0.2794 0.9906) (xy -0.2794 0.9906)
			)
			(stroke
				(width 0)
				(type default)
			)
			(fill no)
			(layer "F.CrtYd")
		)
		(fp_line
			(start 0.2794 0.9906)
			(end 0.2794 -0.1016)
			(stroke
				(width 0.1)
				(type default)
			)
			(layer "F.Fab")
		)
		(fp_line
			(start 0.2794 -0.1016)
			(end -0.2794 -0.1016)
			(stroke
				(width 0.1)
				(type default)
			)
			(layer "F.Fab")
		)
		(fp_line
			(start -0.2794 0.9906)
			(end 0.2794 0.9906)
			(stroke
				(width 0.1)
				(type default)
			)
			(layer "F.Fab")
		)
		(fp_line
			(start -0.2794 -0.1016)
			(end -0.2794 0.9906)
			(stroke
				(width 0.1)
				(type default)
			)
			(layer "F.Fab")
		)
		(pad "1" smd rect
			(at 0 0 180)
			(size 0.508 0.508)
			(layers "F.Cu" "F.Mask" "F.Paste")
			(net "FM_CPU_ERR1_LVT3_N")
		)
		(pad "2" smd rect
			(at 0 0.889 180)
			(size 0.508 0.508)
			(layers "F.Cu" "F.Mask" "F.Paste")
			(net "FM_CPU_ERR1_LVT3_BMC_N")
		)
		(zone
			(layer "F.Cu")
			(hatch none 0.5)
			(connect_pads
				(clearance 0)
			)
			(min_thickness 0.25)
			(keepout
				(tracks not_allowed)
				(vias allowed)
				(pads allowed)
				(copperpour not_allowed)
				(footprints allowed)
			)
			(placement
				(enabled no)
				(sheetname "")
			)
			(fill
				(thermal_gap 0.5)
				(thermal_bridge_width 0.5)
				(island_removal_mode 0)
			)
			(polygon
				(pts
					(xy 406.4 -47.4599) (xy 405.892 -47.4599) (xy 405.892 -47.0789) (xy 406.4 -47.0789)
				)
			)
		)
		(zone
			(layer "F.Cu")
			(hatch none 0.5)
			(connect_pads
				(clearance 0)
			)
			(min_thickness 0.25)
			(keepout
				(tracks allowed)
				(vias not_allowed)
				(pads allowed)
				(copperpour not_allowed)
				(footprints allowed)
			)
			(placement
				(enabled no)
				(sheetname "")
			)
			(fill
				(thermal_gap 0.5)
				(thermal_bridge_width 0.5)
				(island_removal_mode 0)
			)
			(polygon
				(pts
					(xy 406.4 -47.0789) (xy 405.892 -47.0789) (xy 405.892 -47.4599) (xy 406.4 -47.4599)
				)
			)
		)
	)
)
